# BASEBOARD_FAB2 (Tioga Pass) — schematic netlist excerpt (pin names and nets, part order shuffled) for the footprints in the layout excerpt that follows; sources: Cadence DE-HDL packaged netlist, KiCad conversion of Wiwynn_Tioga_Pass_MB.brd

C22W20  SC22U16V5MX-4-GP  20%  pkg SMD-BCG5  page 214 : \1\ = VR_FET_SW_P12V_STBY_PVCCIN_CPU0 ; \2\ = GND
C5G117  CAP  47UF 4V 20% X6S  pkg 0805  page 243 : A = PVDDQ_GHJ ; B = GND
C6P13  CAP  10UF 16V 10% X6S  pkg 0805  page 202 : A = VR_FET_SW_P12V_STBY_PVCCIN_CPU0 ; B = GND
R1R7  RES  20.0K 1% CHIP  pkg 0402  page 140 : A = P3V3_STBY ; B = SPI_NIC_MOSI

(kicad_pcb
	(version 20260206)
	(generator "pcbnew")
	(generator_version "10.0")
	(general
		(thickness 1.6)
		(legacy_teardrops no)
	)
	(paper "A4")
	(title_block
		(title "Wiwynn_Tioga_Pass_MB.brd")
		(comment 1 "Tioga Pass / footprints 2643-2646 of 4770")
	)
	(layers
		(0 "F.Cu" signal "TOP")
		(4 "In1.Cu" signal "L2GND")
		(6 "In2.Cu" signal "L3")
		(8 "In3.Cu" signal "L4GND")
		(10 "In4.Cu" signal "L5")
		(12 "In5.Cu" signal "L6GND")
		(14 "In6.Cu" signal "L7VCC")
		(16 "In7.Cu" signal "L8VCC")
		(18 "In8.Cu" signal "L9GND")
		(20 "In9.Cu" signal "L10")
		(22 "In10.Cu" signal "L11GND")
		(24 "In11.Cu" signal "L12")
		(26 "In12.Cu" signal "L13GND")
		(2 "B.Cu" signal "BOTTOM")
		(9 "F.Adhes" user "F.Adhesive")
		(11 "B.Adhes" user "B.Adhesive")
		(13 "F.Paste" user "Package Geometry/Pastemask Top")
		(15 "B.Paste" user "Package Geometry/Pastemask Bottom")
		(5 "F.SilkS" user "Ref Des/Silkscreen Top")
		(7 "B.SilkS" user "Ref Des/Silkscreen Bottom")
		(1 "F.Mask" user "Board Geometry/Soldermask Top")
		(3 "B.Mask" user "Board Geometry/Soldermask Bottom")
		(17 "Dwgs.User" user "User.Drawings")
		(19 "Cmts.User" user "User.Comments")
		(21 "Eco1.User" user "User.Eco1")
		(23 "Eco2.User" user "User.Eco2")
		(25 "Edge.Cuts" user "Board Geometry/Outline")
		(27 "Margin" user)
		(31 "F.CrtYd" user "Package Geometry/Place Bound Top")
		(29 "B.CrtYd" user "Package Geometry/Place Bound Bottom")
		(35 "F.Fab" user "Ref Des/Assembly Top")
		(33 "B.Fab" user "Ref Des/Assembly Bottom")
	)
	(footprint ""
		(layer "B.Cu")
		(at 179.39258 -60.99683 180)
		(property "Reference" "C22W20"
			(at 0 0 0)
			(layer "B.SilkS")
			(hide yes)
			(effects
				(font
					(size 1.27 1.27)
				)
				(justify mirror)
			)
		)
		(property "Value" "*"
			(at 0.0762 -6.2357 180)
			(unlocked yes)
			(layer "B.Fab")
			(hide yes)
			(effects
				(font
					(size 1.27 1.016)
					(thickness 0.1524)
				)
				(justify mirror)
			)
		)
		(property "Device Type" "SC22U16V5MX-4-GP_SMD-BCG5-SC22A"
			(at 0.0762 -8.2677 180)
			(unlocked yes)
			(layer "B.Fab")
			(hide yes)
			(effects
				(font
					(size 1.27 1.016)
					(thickness 0.1524)
				)
				(justify mirror)
			)
		)
		(duplicate_pad_numbers_are_jumpers no)
		(fp_line
			(start -0.635 0)
			(end 0.635 0)
			(stroke
				(width 0.508)
				(type default)
			)
			(layer "B.SilkS")
		)
		(fp_rect
			(start 0.9652 1.778)
			(end -0.9652 -1.778)
			(stroke
				(width 0)
				(type default)
			)
			(fill no)
			(layer "B.CrtYd")
		)
		(fp_poly
			(pts
				(xy 0.9652 -1.778) (xy -0.9652 -1.778) (xy -0.9652 1.778) (xy 0.9652 1.778)
			)
			(stroke
				(width 0)
				(type default)
			)
			(fill no)
			(layer "B.Fab")
		)
		(pad "1" smd rect
			(at 0 -0.9652)
			(size 1.397 1.143)
			(layers "B.Cu" "B.Mask" "B.Paste")
			(net "VR_FET_SW_P12V_STBY_PVCCIN_CPU0")
		)
		(pad "2" smd rect
			(at 0 0.9652)
			(size 1.397 1.143)
			(layers "B.Cu" "B.Mask" "B.Paste")
			(net "GND")
		)
	)
	(footprint ""
		(layer "B.Cu")
		(at 94.308168 -3.321812 90)
		(property "Reference" "C5G117"
			(at -1.64973 0.78994 180)
			(unlocked yes)
			(layer "B.SilkS")
			(effects
				(font
					(size 0.7874 0.5842)
					(thickness 0.1524)
				)
				(justify mirror)
			)
		)
		(property "Value" ""
			(at 0 0 90)
			(layer "B.Fab")
			(effects
				(font
					(size 1.27 1.27)
				)
				(justify mirror)
			)
		)
		(duplicate_pad_numbers_are_jumpers no)
		(fp_rect
			(start -0.7239 -0.2159)
			(end 0.7239 1.9939)
			(stroke
				(width 0)
				(type default)
			)
			(fill no)
			(layer "B.CrtYd")
		)
		(fp_line
			(start 0.7239 -0.2159)
			(end 0.7239 1.9939)
			(stroke
				(width 0.1)
				(type default)
			)
			(layer "B.Fab")
		)
		(fp_line
			(start -0.7239 -0.2159)
			(end 0.7239 -0.2159)
			(stroke
				(width 0.1)
				(type default)
			)
			(layer "B.Fab")
		)
		(fp_line
			(start 0.7239 1.9939)
			(end -0.7239 1.9939)
			(stroke
				(width 0.1)
				(type default)
			)
			(layer "B.Fab")
		)
		(fp_line
			(start -0.7239 1.9939)
			(end -0.7239 -0.2159)
			(stroke
				(width 0.1)
				(type default)
			)
			(layer "B.Fab")
		)
		(pad "1" smd rect
			(at 0 0 270)
			(size 1.27 1.016)
			(layers "B.Cu" "B.Mask" "B.Paste")
			(net "PVDDQ_GHJ")
		)
		(pad "2" smd rect
			(at 0 1.778 270)
			(size 1.27 1.016)
			(layers "B.Cu" "B.Mask" "B.Paste")
			(net "GND")
		)
		(zone
			(layer "B.Cu")
			(hatch none 0.5)
			(connect_pads
				(clearance 0)
			)
			(min_thickness 0.25)
			(keepout
				(tracks not_allowed)
				(vias allowed)
				(pads allowed)
				(copperpour not_allowed)
				(footprints allowed)
			)
			(placement
				(enabled no)
				(sheetname "")
			)
			(fill
				(thermal_gap 0.5)
				(thermal_bridge_width 0.5)
				(island_removal_mode 0)
			)
			(polygon
				(pts
					(xy 94.816168 -2.686812) (xy 95.578168 -2.686812) (xy 95.578168 -3.956812) (xy 94.816168 -3.956812)
				)
			)
		)
	)
	(footprint ""
		(layer "B.Cu")
		(at 488.09148 -29.3116)
		(property "Reference" "R1R7"
			(at 0.8382 -0.67818 0)
			(unlocked yes)
			(layer "B.SilkS")
			(effects
				(font
					(size 0.4064 0.254)
					(thickness 0.1524)
				)
				(justify left mirror)
			)
		)
		(property "Value" ""
			(at 0 0 0)
			(layer "B.Fab")
			(effects
				(font
					(size 1.27 1.27)
				)
				(justify mirror)
			)
		)
		(duplicate_pad_numbers_are_jumpers no)
		(fp_poly
			(pts
				(xy 0.2794 -0.1016) (xy -0.2794 -0.1016) (xy -0.2794 0.9906) (xy 0.2794 0.9906)
			)
			(stroke
				(width 0)
				(type default)
			)
			(fill no)
			(layer "B.CrtYd")
		)
		(fp_line
			(start -0.2794 -0.1016)
			(end 0.2794 -0.1016)
			(stroke
				(width 0.1)
				(type default)
			)
			(layer "B.Fab")
		)
		(fp_line
			(start -0.2794 0.9906)
			(end -0.2794 -0.1016)
			(stroke
				(width 0.1)
				(type default)
			)
			(layer "B.Fab")
		)
		(fp_line
			(start 0.2794 -0.1016)
			(end 0.2794 0.9906)
			(stroke
				(width 0.1)
				(type default)
			)
			(layer "B.Fab")
		)
		(fp_line
			(start 0.2794 0.9906)
			(end -0.2794 0.9906)
			(stroke
				(width 0.1)
				(type default)
			)
			(layer "B.Fab")
		)
		(pad "1" smd rect
			(at 0 0 180)
			(size 0.508 0.508)
			(layers "B.Cu" "B.Mask" "B.Paste")
			(net "P3V3_STBY")
		)
		(pad "2" smd rect
			(at 0 0.889 180)
			(size 0.508 0.508)
			(layers "B.Cu" "B.Mask" "B.Paste")
			(net "SPI_NIC_MOSI")
		)
		(zone
			(layer "B.Cu")
			(hatch none 0.5)
			(connect_pads
				(clearance 0)
			)
			(min_thickness 0.25)
			(keepout
				(tracks allowed)
				(vias not_allowed)
				(pads allowed)
				(copperpour not_allowed)
				(footprints allowed)
			)
			(placement
				(enabled no)
				(sheetname "")
			)
			(fill
				(thermal_gap 0.5)
				(thermal_bridge_width 0.5)
				(island_removal_mode 0)
			)
			(polygon
				(pts
					(xy 488.34548 -29.0576) (xy 487.83748 -29.0576) (xy 487.83748 -28.6766) (xy 488.34548 -28.6766)
				)
			)
		)
		(zone
			(layer "B.Cu")
			(hatch none 0.5)
			(connect_pads
				(clearance 0)
			)
			(min_thickness 0.25)
			(keepout
				(tracks not_allowed)
				(vias allowed)
				(pads allowed)
				(copperpour not_allowed)
				(footprints allowed)
			)
			(placement
				(enabled no)
				(sheetname "")
			)
			(fill
				(thermal_gap 0.5)
				(thermal_bridge_width 0.5)
				(island_removal_mode 0)
			)
			(polygon
				(pts
					(xy 488.34548 -28.6766) (xy 487.83748 -28.6766) (xy 487.83748 -29.0576) (xy 488.34548 -29.0576)
				)
			)
		)
	)
	(footprint ""
		(layer "B.Cu")
		(at 197.848728 -82.842862 90)
		(property "Reference" "C6P13"
			(at 0 0 90)
			(layer "B.SilkS")
			(hide yes)
			(effects
				(font
					(size 1.27 1.27)
				)
				(justify mirror)
			)
		)
		(property "Value" ""
			(at 0 0 90)
			(layer "B.Fab")
			(effects
				(font
					(size 1.27 1.27)
				)
				(justify mirror)
			)
		)
		(duplicate_pad_numbers_are_jumpers no)
		(fp_rect
			(start 0.7239 1.9939)
			(end -0.7239 -0.2159)
			(stroke
				(width 0)
				(type default)
			)
			(fill no)
			(layer "B.CrtYd")
		)
		(fp_line
			(start 0.7239 -0.2159)
			(end 0.7239 1.9939)
			(stroke
				(width 0.1)
				(type default)
			)
			(layer "B.Fab")
		)
		(fp_line
			(start -0.7239 -0.2159)
			(end 0.7239 -0.2159)
			(stroke
				(width 0.1)
				(type default)
			)
			(layer "B.Fab")
		)
		(fp_line
			(start 0.7239 1.9939)
			(end -0.7239 1.9939)
			(stroke
				(width 0.1)
				(type default)
			)
			(layer "B.Fab")
		)
		(fp_line
			(start -0.7239 1.9939)
			(end -0.7239 -0.2159)
			(stroke
				(width 0.1)
				(type default)
			)
			(layer "B.Fab")
		)
		(pad "1" smd rect
			(at 0 0 270)
			(size 1.27 1.016)
			(layers "B.Cu" "B.Mask" "B.Paste")
			(net "VR_FET_SW_P12V_STBY_PVCCIN_CPU0")
		)
		(pad "2" smd rect
			(at 0 1.778 270)
			(size 1.27 1.016)
			(layers "B.Cu" "B.Mask" "B.Paste")
			(net "GND")
		)
		(zone
			(layer "B.Cu")
			(hatch none 0.5)
			(connect_pads
				(clearance 0)
			)
			(min_thickness 0.25)
			(keepout
				(tracks not_allowed)
				(vias allowed)
				(pads allowed)
				(copperpour not_allowed)
				(footprints allowed)
			)
			(placement
				(enabled no)
				(sheetname "")
			)
			(fill
				(thermal_gap 0.5)
				(thermal_bridge_width 0.5)
				(island_removal_mode 0)
			)
			(polygon
				(pts
					(xy 199.118728 -83.477862) (xy 198.356728 -83.477862) (xy 198.356728 -82.207862) (xy 199.118728 -82.207862)
				)
			)
		)
	)
)
